# SCM (Grand Teton) — schematic netlist excerpt (pin names and nets, part order shuffled) for the footprints in the layout excerpt that follows; sources: Cadence DE-HDL packaged netlist, KiCad conversion of 12092022_DA0F0TMDCD0_F0T_Management_Board_D_brd_V3_OCP.brd

R509  Q_RES  33.2 1% CHIP  pkg 0402LF  page 48 : A = MB_JTAG_PLD_R_JTAGEN ; B = JTAG_SCM_PLD_JTAGEN
C147  Q_CAP  0.1UF 25V 10% EMPTY  pkg 0402  page 22 : A = P3V3_AUX ; B = GND

(kicad_pcb
	(version 20260206)
	(generator "pcbnew")
	(generator_version "10.0")
	(general
		(thickness 1.6)
		(legacy_teardrops no)
	)
	(paper "A4")
	(title_block
		(title "12092022_DA0F0TMDCD0_F0T_Management_Board_D_brd_V3_OCP.brd")
		(comment 1 "Grand Teton / footprints 345-346 of 1440")
	)
	(layers
		(0 "F.Cu" signal "TOP")
		(4 "In1.Cu" signal "GND")
		(6 "In2.Cu" signal "IN1")
		(8 "In3.Cu" signal "GND1")
		(10 "In4.Cu" signal "IN2")
		(12 "In5.Cu" signal "VCC")
		(14 "In6.Cu" signal "VCC1")
		(16 "In7.Cu" signal "IN3")
		(18 "In8.Cu" signal "GND2")
		(20 "In9.Cu" signal "IN4")
		(22 "In10.Cu" signal "GND3")
		(2 "B.Cu" signal "BOTTOM")
		(9 "F.Adhes" user "F.Adhesive")
		(11 "B.Adhes" user "B.Adhesive")
		(13 "F.Paste" user "Package Geometry/Pastemask Top")
		(15 "B.Paste" user "Package Geometry/Pastemask Bottom")
		(5 "F.SilkS" user "Ref Des/Silkscreen Top")
		(7 "B.SilkS" user "Ref Des/Silkscreen Bottom")
		(1 "F.Mask" user "Board Geometry/Soldermask Top")
		(3 "B.Mask" user "Board Geometry/Soldermask Bottom")
		(17 "Dwgs.User" user "User.Drawings")
		(19 "Cmts.User" user "User.Comments")
		(21 "Eco1.User" user "User.Eco1")
		(23 "Eco2.User" user "User.Eco2")
		(25 "Edge.Cuts" user "Board Geometry/Outline")
		(27 "Margin" user)
		(31 "F.CrtYd" user "Package Geometry/Place Bound Top")
		(29 "B.CrtYd" user "Package Geometry/Place Bound Bottom")
		(35 "F.Fab" user "Ref Des/Assembly Top")
		(33 "B.Fab" user "Ref Des/Assembly Bottom")
	)
	(footprint ""
		(layer "F.Cu")
		(at 16.8275 -106.6165 -90)
		(property "Reference" "C147"
			(at 0 0 270)
			(layer "F.SilkS")
			(hide yes)
			(effects
				(font
					(size 1.27 1.27)
				)
			)
		)
		(property "Value" ""
			(at 0 0 270)
			(layer "F.Fab")
			(effects
				(font
					(size 1.27 1.27)
				)
			)
		)
		(duplicate_pad_numbers_are_jumpers no)
		(fp_line
			(start -0.7874 0.4064)
			(end -0.7874 -0.4064)
			(stroke
				(width 0.1524)
				(type default)
			)
			(layer "F.SilkS")
		)
		(fp_line
			(start 0.7874 0.4064)
			(end -0.7874 0.4064)
			(stroke
				(width 0.1524)
				(type default)
			)
			(layer "F.SilkS")
		)
		(fp_line
			(start -0.7874 -0.4064)
			(end 0.7874 -0.4064)
			(stroke
				(width 0.1524)
				(type default)
			)
			(layer "F.SilkS")
		)
		(fp_line
			(start 0.7874 -0.4064)
			(end 0.7874 0.4064)
			(stroke
				(width 0.1524)
				(type default)
			)
			(layer "F.SilkS")
		)
		(fp_line
			(start -0.67945 0.3048)
			(end -0.67945 -0.305054)
			(stroke
				(width 0.1)
				(type default)
			)
			(layer "F.Fab")
		)
		(fp_line
			(start -0.12065 0.3048)
			(end -0.67945 0.3048)
			(stroke
				(width 0.1)
				(type default)
			)
			(layer "F.Fab")
		)
		(fp_line
			(start 0.120396 0.3048)
			(end 0.120396 0.2794)
			(stroke
				(width 0.1)
				(type default)
			)
			(layer "F.Fab")
		)
		(fp_line
			(start 0.67945 0.3048)
			(end 0.120396 0.3048)
			(stroke
				(width 0.1)
				(type default)
			)
			(layer "F.Fab")
		)
		(fp_line
			(start -0.12065 0.2794)
			(end -0.12065 0.3048)
			(stroke
				(width 0.1)
				(type default)
			)
			(layer "F.Fab")
		)
		(fp_line
			(start 0.120396 0.2794)
			(end -0.12065 0.2794)
			(stroke
				(width 0.1)
				(type default)
			)
			(layer "F.Fab")
		)
		(fp_line
			(start -0.12065 -0.2794)
			(end 0.12065 -0.2794)
			(stroke
				(width 0.1)
				(type default)
			)
			(layer "F.Fab")
		)
		(fp_line
			(start 0.12065 -0.2794)
			(end 0.12065 -0.3048)
			(stroke
				(width 0.1)
				(type default)
			)
			(layer "F.Fab")
		)
		(fp_line
			(start 0.12065 -0.3048)
			(end 0.67945 -0.3048)
			(stroke
				(width 0.1)
				(type default)
			)
			(layer "F.Fab")
		)
		(fp_line
			(start 0.67945 -0.3048)
			(end 0.67945 0.3048)
			(stroke
				(width 0.1)
				(type default)
			)
			(layer "F.Fab")
		)
		(fp_line
			(start -0.67945 -0.305054)
			(end -0.12065 -0.305054)
			(stroke
				(width 0.1)
				(type default)
			)
			(layer "F.Fab")
		)
		(fp_line
			(start -0.12065 -0.305054)
			(end -0.12065 -0.2794)
			(stroke
				(width 0.1)
				(type default)
			)
			(layer "F.Fab")
		)
		(pad "1" smd circle
			(at -0.40005 0 270)
			(size 0 0)
			(layers "F.Cu" "F.Mask" "F.Paste")
			(net "P3V3_AUX")
		)
		(pad "2" smd circle
			(at 0.40005 0 270)
			(size 0 0)
			(layers "F.Cu" "F.Mask" "F.Paste")
			(net "GND")
		)
	)
	(footprint ""
		(layer "F.Cu")
		(at 59.6392 -81.1276 180)
		(property "Reference" "R509"
			(at 0 0 180)
			(layer "F.SilkS")
			(hide yes)
			(effects
				(font
					(size 1.27 1.27)
				)
			)
		)
		(property "Value" ""
			(at 0 0 180)
			(layer "F.Fab")
			(effects
				(font
					(size 1.27 1.27)
				)
			)
		)
		(duplicate_pad_numbers_are_jumpers no)
		(fp_line
			(start 0.7874 0.4064)
			(end -0.7874 0.4064)
			(stroke
				(width 0.1524)
				(type default)
			)
			(layer "F.SilkS")
		)
		(fp_line
			(start 0.7874 -0.4064)
			(end 0.7874 0.4064)
			(stroke
				(width 0.1524)
				(type default)
			)
			(layer "F.SilkS")
		)
		(fp_line
			(start -0.7874 0.4064)
			(end -0.7874 -0.4064)
			(stroke
				(width 0.1524)
				(type default)
			)
			(layer "F.SilkS")
		)
		(fp_line
			(start -0.7874 -0.4064)
			(end 0.7874 -0.4064)
			(stroke
				(width 0.1524)
				(type default)
			)
			(layer "F.SilkS")
		)
		(fp_line
			(start 0.67945 0.3048)
			(end 0.120396 0.3048)
			(stroke
				(width 0.1)
				(type default)
			)
			(layer "F.Fab")
		)
		(fp_line
			(start 0.67945 -0.3048)
			(end 0.67945 0.3048)
			(stroke
				(width 0.1)
				(type default)
			)
			(layer "F.Fab")
		)
		(fp_line
			(start 0.12065 -0.2794)
			(end 0.12065 -0.3048)
			(stroke
				(width 0.1)
				(type default)
			)
			(layer "F.Fab")
		)
		(fp_line
			(start 0.12065 -0.3048)
			(end 0.67945 -0.3048)
			(stroke
				(width 0.1)
				(type default)
			)
			(layer "F.Fab")
		)
		(fp_line
			(start 0.120396 0.3048)
			(end 0.120396 0.2794)
			(stroke
				(width 0.1)
				(type default)
			)
			(layer "F.Fab")
		)
		(fp_line
			(start 0.120396 0.2794)
			(end -0.12065 0.2794)
			(stroke
				(width 0.1)
				(type default)
			)
			(layer "F.Fab")
		)
		(fp_line
			(start -0.12065 0.3048)
			(end -0.67945 0.3048)
			(stroke
				(width 0.1)
				(type default)
			)
			(layer "F.Fab")
		)
		(fp_line
			(start -0.12065 0.2794)
			(end -0.12065 0.3048)
			(stroke
				(width 0.1)
				(type default)
			)
			(layer "F.Fab")
		)
		(fp_line
			(start -0.12065 -0.2794)
			(end 0.12065 -0.2794)
			(stroke
				(width 0.1)
				(type default)
			)
			(layer "F.Fab")
		)
		(fp_line
			(start -0.12065 -0.305054)
			(end -0.12065 -0.2794)
			(stroke
				(width 0.1)
				(type default)
			)
			(layer "F.Fab")
		)
		(fp_line
			(start -0.67945 0.3048)
			(end -0.67945 -0.305054)
			(stroke
				(width 0.1)
				(type default)
			)
			(layer "F.Fab")
		)
		(fp_line
			(start -0.67945 -0.305054)
			(end -0.12065 -0.305054)
			(stroke
				(width 0.1)
				(type default)
			)
			(layer "F.Fab")
		)
		(pad "1" smd circle
			(at -0.40005 0 180)
			(size 0 0)
			(layers "F.Cu" "F.Mask" "F.Paste")
			(net "MB_JTAG_PLD_R_JTAGEN")
		)
		(pad "2" smd circle
			(at 0.40005 0 180)
			(size 0 0)
			(layers "F.Cu" "F.Mask" "F.Paste")
			(net "JTAG_SCM_PLD_JTAGEN")
		)
	)
)
